(kicad_pcb
	(version 20241229)
	(generator "pcbnew")
	(generator_version "9.0")
	(general
		(thickness 1.711)
		(legacy_teardrops no)
	)
	(paper "A4")
	(title_block
		(title "Antmicro Baseboard for Jetson AGX Thor")
		(date "2026-02-18")
		(rev "1.1.0")
		(company "Antmicro Ltd")
		(comment 1 "www.antmicro.com")
		(comment 9 "footprints 217-221 of 1170")
	)
	(layers
		(0 "F.Cu" signal)
		(4 "In1.Cu" signal)
		(6 "In2.Cu" signal)
		(8 "In3.Cu" signal)
		(10 "In4.Cu" jumper)
		(12 "In5.Cu" signal)
		(14 "In6.Cu" signal)
		(16 "In7.Cu" signal)
		(18 "In8.Cu" signal)
		(2 "B.Cu" signal)
		(9 "F.Adhes" user "F.Adhesive")
		(11 "B.Adhes" user "B.Adhesive")
		(13 "F.Paste" user)
		(15 "B.Paste" user)
		(5 "F.SilkS" user "F.Silkscreen")
		(7 "B.SilkS" user "B.Silkscreen")
		(1 "F.Mask" user)
		(3 "B.Mask" user)
		(17 "Dwgs.User" user "User.Drawings")
		(19 "Cmts.User" user "User.Comments")
		(21 "Eco1.User" user "User.Eco1")
		(23 "Eco2.User" user "User.Eco2")
		(25 "Edge.Cuts" user)
		(27 "Margin" user)
		(31 "F.CrtYd" user "F.Courtyard")
		(29 "B.CrtYd" user "B.Courtyard")
		(35 "F.Fab" user)
		(33 "B.Fab" user)
	)
	(footprint "antmicro-footprints:C_0402_1005Metric"
		(layer "F.Cu")
		(at 105.39 57.179999 -90)
		(descr "Capacitor SMD 0402")
		(tags "capacitor SMD 0402")
		(property "Reference" "C382"
			(at 0.840001 0.53 90)
			(layer "F.SilkS")
			(effects
				(font
					(size 0.7 0.7)
					(thickness 0.15)
				)
				(justify right top)
			)
		)
		(property "Value" "C_100n_0402"
			(at -1.022927 2.155213 90)
			(layer "F.Fab")
			(effects
				(font
					(size 0.7 0.7)
					(thickness 0.15)
				)
				(justify right top)
			)
		)
		(property "Datasheet" "https://www.murata.com/products/productdetail?partno=GRM155R61H104KE14%23"
			(at 0 0 90)
			(layer "F.Fab")
			(hide yes)
			(effects
				(font
					(size 1.27 1.27)
					(thickness 0.15)
				)
			)
		)
		(property "Description" "SMD Multilayer Ceramic Capacitor, 0.1 µF, 50 V, 0402 [1005 Metric], ± 10%, X5R, GRM Series"
			(at 0 0 90)
			(layer "F.Fab")
			(hide yes)
			(effects
				(font
					(size 1.27 1.27)
					(thickness 0.15)
				)
			)
		)
		(property "Manufacturer" "Murata"
			(at 0 0 270)
			(unlocked yes)
			(layer "F.Fab")
			(hide yes)
			(effects
				(font
					(size 1 1)
					(thickness 0.15)
				)
			)
		)
		(property "MPN" "GRM155R61H104KE14D"
			(at 0 0 270)
			(unlocked yes)
			(layer "F.Fab")
			(hide yes)
			(effects
				(font
					(size 1 1)
					(thickness 0.15)
				)
			)
		)
		(property "Val" "100n"
			(at 0 0 270)
			(unlocked yes)
			(layer "F.Fab")
			(hide yes)
			(effects
				(font
					(size 1 1)
					(thickness 0.15)
				)
			)
		)
		(property "License" "Apache-2.0"
			(at 0 0 270)
			(unlocked yes)
			(layer "F.Fab")
			(hide yes)
			(effects
				(font
					(size 1 1)
					(thickness 0.15)
				)
			)
		)
		(property "Author" "Antmicro"
			(at 0 0 270)
			(unlocked yes)
			(layer "F.Fab")
			(hide yes)
			(effects
				(font
					(size 1 1)
					(thickness 0.15)
				)
			)
		)
		(property "Voltage" "50V"
			(at 0 0 270)
			(unlocked yes)
			(layer "F.Fab")
			(hide yes)
			(effects
				(font
					(size 1 1)
					(thickness 0.15)
				)
			)
		)
		(property "Dielectric" "X5R"
			(at 0 0 270)
			(unlocked yes)
			(layer "F.Fab")
			(hide yes)
			(effects
				(font
					(size 1 1)
					(thickness 0.15)
				)
			)
		)
		(sheetname "/DCDC/")
		(sheetfile "dcdc.kicad_sch")
		(attr smd)
		(fp_poly
			(pts
				(xy -0.925 -0.47) (xy 0.925 -0.47) (xy 0.925 0.47) (xy -0.925 0.47)
			)
			(stroke
				(width 0.05)
				(type default)
			)
			(fill no)
			(layer "F.CrtYd")
		)
		(fp_line
			(start -0.494 0.248)
			(end -0.494 -0.25)
			(stroke
				(width 0.15)
				(type solid)
			)
			(layer "F.Fab")
		)
		(fp_line
			(start 0.504 0.248)
			(end -0.494 0.248)
			(stroke
				(width 0.15)
				(type solid)
			)
			(layer "F.Fab")
		)
		(fp_line
			(start -0.494 -0.25)
			(end 0.504 -0.25)
			(stroke
				(width 0.15)
				(type solid)
			)
			(layer "F.Fab")
		)
		(fp_line
			(start 0.504 -0.25)
			(end 0.504 0.248)
			(stroke
				(width 0.15)
				(type solid)
			)
			(layer "F.Fab")
		)
		(fp_text user "License: Apache-2.0"
			(at -0.939 5.799 90)
			(layer "F.Fab")
			(effects
				(font
					(size 0.7 0.7)
					(thickness 0.15)
				)
				(justify right top)
			)
		)
		(fp_text user "Author: Antmicro"
			(at -0.939 3.399 90)
			(layer "F.Fab")
			(effects
				(font
					(size 0.7 0.7)
					(thickness 0.15)
				)
				(justify right top)
			)
		)
		(fp_text user "${REFERENCE}"
			(at -0.939 4.599 90)
			(layer "F.Fab")
			(effects
				(font
					(size 0.7 0.7)
					(thickness 0.15)
				)
				(justify right top)
			)
		)
		(pad "1" smd roundrect
			(at -0.48 0 270)
			(size 0.59 0.64)
			(layers "F.Cu" "F.Mask" "F.Paste")
			(roundrect_rratio 0.25)
			(net 1279 "Net-(U76-IN-)")
			(pintype "passive")
		)
		(pad "2" smd roundrect
			(at 0.48 0 270)
			(size 0.59 0.64)
			(layers "F.Cu" "F.Mask" "F.Paste")
			(roundrect_rratio 0.25)
			(net 1280 "Net-(U76-IN+)")
			(pintype "passive")
		)
	)
	(footprint "antmicro-footprints:SOT-523"
		(layer "F.Cu")
		(at 109.76 63.95 -90)
		(property "Reference" "Q6"
			(at 0.39 2.48 0)
			(layer "F.SilkS")
			(effects
				(font
					(size 0.7 0.7)
					(thickness 0.15)
				)
				(justify left bottom)
			)
		)
		(property "Value" "DMG1012T-7"
			(at 0.1 1.824 90)
			(layer "F.Fab")
			(effects
				(font
					(size 0.7 0.7)
					(thickness 0.15)
				)
				(justify right top)
			)
		)
		(property "Datasheet" "https://www.diodes.com/assets/Datasheets/ds31783.pdf"
			(at 0 0 90)
			(layer "F.Fab")
			(hide yes)
			(effects
				(font
					(size 1.27 1.27)
					(thickness 0.15)
				)
			)
		)
		(property "Description" "Power MOSFET, N Channel, 20 V, 630 mA, 0.3 ohm, SOT-523, Surface Mount"
			(at 0 0 90)
			(layer "F.Fab")
			(hide yes)
			(effects
				(font
					(size 1.27 1.27)
					(thickness 0.15)
				)
			)
		)
		(property "MPN" "DMG1012T-7"
			(at 0 0 270)
			(unlocked yes)
			(layer "F.Fab")
			(hide yes)
			(effects
				(font
					(size 1 1)
					(thickness 0.15)
				)
			)
		)
		(property "Manufacturer" "Diodes Incorporated"
			(at 0 0 270)
			(unlocked yes)
			(layer "F.Fab")
			(hide yes)
			(effects
				(font
					(size 1 1)
					(thickness 0.15)
				)
			)
		)
		(property "Author" "Antmicro"
			(at 0 0 270)
			(unlocked yes)
			(layer "F.Fab")
			(hide yes)
			(effects
				(font
					(size 1 1)
					(thickness 0.15)
				)
			)
		)
		(property "License" "Apache-2.0"
			(at 0 0 270)
			(unlocked yes)
			(layer "F.Fab")
			(hide yes)
			(effects
				(font
					(size 1 1)
					(thickness 0.15)
				)
			)
		)
		(sheetname "/SoM_Power/")
		(sheetfile "som_power.kicad_sch")
		(attr smd)
		(fp_line
			(start -0.927 -0.050999)
			(end -0.927 -0.350999)
			(stroke
				(width 0.15)
				(type solid)
			)
			(layer "F.SilkS")
		)
		(fp_line
			(start -0.927 -0.350999)
			(end -0.725 -0.551)
			(stroke
				(width 0.15)
				(type solid)
			)
			(layer "F.SilkS")
		)
		(fp_line
			(start -0.725 -0.551)
			(end -0.277 -0.551)
			(stroke
				(width 0.15)
				(type solid)
			)
			(layer "F.SilkS")
		)
		(fp_line
			(start -0.277 -0.551)
			(end -0.277 -0.750001)
			(stroke
				(width 0.15)
				(type solid)
			)
			(layer "F.SilkS")
		)
		(fp_circle
			(center -0.9652 0.9652)
			(end -0.915201 0.9652)
			(stroke
				(width 0.15)
				(type solid)
			)
			(fill yes)
			(layer "F.SilkS")
		)
		(fp_line
			(start -1.12 1.15)
			(end 1.1 1.15)
			(stroke
				(width 0.05)
				(type solid)
			)
			(layer "F.CrtYd")
		)
		(fp_line
			(start -1.12 -1.159999)
			(end -1.12 1.15)
			(stroke
				(width 0.05)
				(type solid)
			)
			(layer "F.CrtYd")
		)
		(fp_line
			(start -1.12 -1.159999)
			(end 1.1 -1.159999)
			(stroke
				(width 0.05)
				(type solid)
			)
			(layer "F.CrtYd")
		)
		(fp_line
			(start 1.1 -1.159999)
			(end 1.1 1.15)
			(stroke
				(width 0.05)
				(type solid)
			)
			(layer "F.CrtYd")
		)
		(fp_line
			(start 0.8 0.424)
			(end -0.802 0.424)
			(stroke
				(width 0.15)
				(type solid)
			)
			(layer "F.Fab")
		)
		(fp_line
			(start -0.802 -0.276)
			(end -0.802 0.424)
			(stroke
				(width 0.15)
				(type solid)
			)
			(layer "F.Fab")
		)
		(fp_line
			(start -0.652 -0.425)
			(end -0.802 -0.276)
			(stroke
				(width 0.15)
				(type solid)
			)
			(layer "F.Fab")
		)
		(fp_line
			(start 0.8 -0.425)
			(end 0.8 0.424)
			(stroke
				(width 0.15)
				(type solid)
			)
			(layer "F.Fab")
		)
		(fp_line
			(start 0.8 -0.425)
			(end -0.652 -0.425)
			(stroke
				(width 0.15)
				(type solid)
			)
			(layer "F.Fab")
		)
		(fp_circle
			(center -0.9652 0.9652)
			(end -0.9144 0.9652)
			(stroke
				(width 0.15)
				(type solid)
			)
			(fill no)
			(layer "F.Fab")
		)
		(fp_text user "${REFERENCE}"
			(at -1.12 3.824 90)
			(layer "F.Fab")
			(effects
				(font
					(size 0.7 0.7)
					(thickness 0.15)
				)
				(justify right top)
			)
		)
		(fp_text user "Author: Antmicro"
			(at -1.12 6.224 90)
			(layer "F.Fab")
			(effects
				(font
					(size 0.7 0.7)
					(thickness 0.15)
				)
				(justify right top)
			)
		)
		(fp_text user "License: Apache-2.0"
			(at -1.12 5.024 90)
			(layer "F.Fab")
			(effects
				(font
					(size 0.7 0.7)
					(thickness 0.15)
				)
				(justify right top)
			)
		)
		(pad "1" smd rect
			(at -0.5 0.65 270)
			(size 0.4 0.51)
			(layers "F.Cu" "F.Mask" "F.Paste")
			(net 1285 "/SoM_Power/VIN_PWR_ON")
			(pinfunction "G")
			(pintype "input")
		)
		(pad "2" smd rect
			(at 0.498 0.65 270)
			(size 0.4 0.51)
			(layers "F.Cu" "F.Mask" "F.Paste")
			(net 1 "GND")
			(pinfunction "S")
			(pintype "passive")
		)
		(pad "3" smd rect
			(at 0 -0.652001 270)
			(size 0.4 0.51)
			(layers "F.Cu" "F.Mask" "F.Paste")
			(net 1392 "Net-(Q6-D)")
			(pinfunction "D")
			(pintype "passive")
		)
	)
	(footprint "antmicro-footprints:C_0402_1005Metric"
		(layer "F.Cu")
		(at 218.795 118.9 180)
		(descr "Capacitor SMD 0402")
		(tags "capacitor SMD 0402")
		(property "Reference" "C101"
			(at -1.005 2.4 0)
			(layer "F.SilkS")
			(effects
				(font
					(size 0.7 0.7)
					(thickness 0.15)
				)
				(justify right top)
			)
		)
		(property "Value" "C_100n_0402"
			(at -1.022927 2.155213 0)
			(layer "F.Fab")
			(effects
				(font
					(size 0.7 0.7)
					(thickness 0.15)
				)
				(justify right top)
			)
		)
		(property "Datasheet" "https://www.murata.com/products/productdetail?partno=GRM155R61H104KE14%23"
			(at 0 0 0)
			(layer "F.Fab")
			(hide yes)
			(effects
				(font
					(size 1.27 1.27)
					(thickness 0.15)
				)
			)
		)
		(property "Description" "SMD Multilayer Ceramic Capacitor, 0.1 µF, 50 V, 0402 [1005 Metric], ± 10%, X5R, GRM Series"
			(at 0 0 0)
			(layer "F.Fab")
			(hide yes)
			(effects
				(font
					(size 1.27 1.27)
					(thickness 0.15)
				)
			)
		)
		(property "Manufacturer" "Murata"
			(at 0 0 180)
			(unlocked yes)
			(layer "F.Fab")
			(hide yes)
			(effects
				(font
					(size 1 1)
					(thickness 0.15)
				)
			)
		)
		(property "MPN" "GRM155R61H104KE14D"
			(at 0 0 180)
			(unlocked yes)
			(layer "F.Fab")
			(hide yes)
			(effects
				(font
					(size 1 1)
					(thickness 0.15)
				)
			)
		)
		(property "Val" "100n"
			(at 0 0 180)
			(unlocked yes)
			(layer "F.Fab")
			(hide yes)
			(effects
				(font
					(size 1 1)
					(thickness 0.15)
				)
			)
		)
		(property "License" "Apache-2.0"
			(at 0 0 180)
			(unlocked yes)
			(layer "F.Fab")
			(hide yes)
			(effects
				(font
					(size 1 1)
					(thickness 0.15)
				)
			)
		)
		(property "Author" "Antmicro"
			(at 0 0 180)
			(unlocked yes)
			(layer "F.Fab")
			(hide yes)
			(effects
				(font
					(size 1 1)
					(thickness 0.15)
				)
			)
		)
		(property "Voltage" "50V"
			(at 0 0 180)
			(unlocked yes)
			(layer "F.Fab")
			(hide yes)
			(effects
				(font
					(size 1 1)
					(thickness 0.15)
				)
			)
		)
		(property "Dielectric" "X5R"
			(at 0 0 180)
			(unlocked yes)
			(layer "F.Fab")
			(hide yes)
			(effects
				(font
					(size 1 1)
					(thickness 0.15)
				)
			)
		)
		(sheetname "/USB Hub/")
		(sheetfile "usb_hub.kicad_sch")
		(attr smd)
		(fp_rect
			(start -0.925 -0.47)
			(end 0.925 0.47)
			(stroke
				(width 0.05)
				(type default)
			)
			(fill no)
			(layer "F.CrtYd")
		)
		(fp_line
			(start 0.504 0.248)
			(end -0.494 0.248)
			(stroke
				(width 0.15)
				(type solid)
			)
			(layer "F.Fab")
		)
		(fp_line
			(start 0.504 -0.25)
			(end 0.504 0.248)
			(stroke
				(width 0.15)
				(type solid)
			)
			(layer "F.Fab")
		)
		(fp_line
			(start -0.494 0.248)
			(end -0.494 -0.25)
			(stroke
				(width 0.15)
				(type solid)
			)
			(layer "F.Fab")
		)
		(fp_line
			(start -0.494 -0.25)
			(end 0.504 -0.25)
			(stroke
				(width 0.15)
				(type solid)
			)
			(layer "F.Fab")
		)
		(fp_text user "Author: Antmicro"
			(at -0.939 3.399 0)
			(layer "F.Fab")
			(effects
				(font
					(size 0.7 0.7)
					(thickness 0.15)
				)
				(justify right top)
			)
		)
		(fp_text user "${REFERENCE}"
			(at -0.939 4.599 0)
			(layer "F.Fab")
			(effects
				(font
					(size 0.7 0.7)
					(thickness 0.15)
				)
				(justify right top)
			)
		)
		(fp_text user "License: Apache-2.0"
			(at -0.939 5.799 0)
			(layer "F.Fab")
			(effects
				(font
					(size 0.7 0.7)
					(thickness 0.15)
				)
				(justify right top)
			)
		)
		(pad "1" smd roundrect
			(at -0.48 0 180)
			(size 0.59 0.64)
			(layers "F.Cu" "F.Mask" "F.Paste")
			(roundrect_rratio 0.25)
			(net 95 "/USB Hub/USBC3_CONN_TX1_N")
			(pintype "passive")
		)
		(pad "2" smd roundrect
			(at 0.48 0 180)
			(size 0.59 0.64)
			(layers "F.Cu" "F.Mask" "F.Paste")
			(roundrect_rratio 0.25)
			(net 45 "/USB Hub/USBC3_TX_{1}+")
			(pintype "passive")
		)
	)
	(footprint "antmicro-footprints:R_0402_1005Metric"
		(layer "F.Cu")
		(at 187.25 59.25 90)
		(descr "Resistor SMD 0402")
		(tags "resistor SMD 0402")
		(property "Reference" "R238"
			(at -2.15 -0.55 90)
			(layer "F.SilkS")
			(effects
				(font
					(size 0.7 0.7)
					(thickness 0.15)
				)
				(justify left bottom)
			)
		)
		(property "Value" "R_10k_0402"
			(at -1.011843 1.772046 90)
			(layer "F.Fab")
			(effects
				(font
					(size 0.7 0.7)
					(thickness 0.15)
				)
				(justify left bottom)
			)
		)
		(property "Datasheet" "https://www.bourns.com/docs/product-datasheets/cr.pdf"
			(at 0 0 90)
			(layer "F.Fab")
			(hide yes)
			(effects
				(font
					(size 1.27 1.27)
					(thickness 0.15)
				)
			)
		)
		(property "Description" "SMD Chip Resistor, 10 kohm, ± 1%, 62.5 mW, 0402 [1005 Metric], Thick Film, General Purpose"
			(at 0 0 90)
			(layer "F.Fab")
			(hide yes)
			(effects
				(font
					(size 1.27 1.27)
					(thickness 0.15)
				)
			)
		)
		(property "Manufacturer" "Bourns"
			(at 0 0 90)
			(unlocked yes)
			(layer "F.Fab")
			(hide yes)
			(effects
				(font
					(size 1 1)
					(thickness 0.15)
				)
			)
		)
		(property "MPN" "CR0402-FX-1002GLF"
			(at 0 0 90)
			(unlocked yes)
			(layer "F.Fab")
			(hide yes)
			(effects
				(font
					(size 1 1)
					(thickness 0.15)
				)
			)
		)
		(property "Val" "10k"
			(at 0 0 90)
			(unlocked yes)
			(layer "F.Fab")
			(hide yes)
			(effects
				(font
					(size 1 1)
					(thickness 0.15)
				)
			)
		)
		(property "License" "Apache-2.0"
			(at 0 0 90)
			(unlocked yes)
			(layer "F.Fab")
			(hide yes)
			(effects
				(font
					(size 1 1)
					(thickness 0.15)
				)
			)
		)
		(property "Author" "Antmicro"
			(at 0 0 90)
			(unlocked yes)
			(layer "F.Fab")
			(hide yes)
			(effects
				(font
					(size 1 1)
					(thickness 0.15)
				)
			)
		)
		(property "Tolerance" "1%"
			(at 0 0 90)
			(unlocked yes)
			(layer "F.Fab")
			(hide yes)
			(effects
				(font
					(size 1 1)
					(thickness 0.15)
				)
			)
		)
		(sheetname "/Peripherals/")
		(sheetfile "peripherals.kicad_sch")
		(attr smd)
		(fp_poly
			(pts
				(xy -0.925 -0.47) (xy 0.925 -0.47) (xy 0.925 0.47) (xy -0.925 0.47)
			)
			(stroke
				(width 0.05)
				(type default)
			)
			(fill no)
			(layer "F.CrtYd")
		)
		(fp_poly
			(pts
				(xy -0.5 -0.25) (xy 0.5 -0.25) (xy 0.5 0.25) (xy -0.5 0.25)
			)
			(stroke
				(width 0.15)
				(type solid)
			)
			(fill no)
			(layer "F.Fab")
		)
		(fp_text user "${REFERENCE}"
			(at -0.95 3.168 90)
			(layer "F.Fab")
			(effects
				(font
					(size 0.7 0.7)
					(thickness 0.15)
				)
				(justify left bottom)
			)
		)
		(fp_text user "License: Apache-2.0"
			(at -0.949999 5.169 90)
			(layer "F.Fab")
			(effects
				(font
					(size 0.7 0.7)
					(thickness 0.15)
				)
				(justify left bottom)
			)
		)
		(fp_text user "Author: Antmicro"
			(at -0.95 4.169 90)
			(layer "F.Fab")
			(effects
				(font
					(size 0.7 0.7)
					(thickness 0.15)
				)
				(justify left bottom)
			)
		)
		(pad "1" smd roundrect
			(at -0.48 0 90)
			(size 0.59 0.64)
			(layers "F.Cu" "F.Mask" "F.Paste")
			(roundrect_rratio 0.25)
			(net 356 "/Expansion connector/GPIO.USER_BTN1")
			(pintype "passive")
		)
		(pad "2" smd roundrect
			(at 0.48 0 90)
			(size 0.59 0.64)
			(layers "F.Cu" "F.Mask" "F.Paste")
			(roundrect_rratio 0.25)
			(net 11 "+1V8")
			(pintype "passive")
		)
	)
	(footprint "antmicro-footprints:R_0402_1005Metric"
		(layer "F.Cu")
		(at 62.12 85.93 -90)
		(descr "Resistor SMD 0402")
		(tags "resistor SMD 0402")
		(property "Reference" "R173"
			(at -3.73 0.42 90)
			(layer "F.SilkS")
			(effects
				(font
					(size 0.7 0.7)
					(thickness 0.15)
				)
				(justify right top)
			)
		)
		(property "Value" "R_4k7_0402"
			(at -1.011843 1.772047 90)
			(layer "F.Fab")
			(effects
				(font
					(size 0.7 0.7)
					(thickness 0.15)
				)
				(justify right top)
			)
		)
		(property "Datasheet" "https://www.bourns.com/docs/product-datasheets/cr.pdf"
			(at 0 0 90)
			(layer "F.Fab")
			(hide yes)
			(effects
				(font
					(size 1.27 1.27)
					(thickness 0.15)
				)
			)
		)
		(property "Description" "SMD Chip Resistor, 4.7 kohm, ± 1%, 62.5 mW, 0402 [1005 Metric], Thick Film, General Purpose"
			(at 0 0 90)
			(layer "F.Fab")
			(hide yes)
			(effects
				(font
					(size 1.27 1.27)
					(thickness 0.15)
				)
			)
		)
		(property "Manufacturer" "Bourns"
			(at 0 0 270)
			(unlocked yes)
			(layer "F.Fab")
			(hide yes)
			(effects
				(font
					(size 1 1)
					(thickness 0.15)
				)
			)
		)
		(property "MPN" "CR0402-FX-4701GLF"
			(at 0 0 270)
			(unlocked yes)
			(layer "F.Fab")
			(hide yes)
			(effects
				(font
					(size 1 1)
					(thickness 0.15)
				)
			)
		)
		(property "Val" "4k7"
			(at 0 0 270)
			(unlocked yes)
			(layer "F.Fab")
			(hide yes)
			(effects
				(font
					(size 1 1)
					(thickness 0.15)
				)
			)
		)
		(property "License" "Apache-2.0"
			(at 0 0 270)
			(unlocked yes)
			(layer "F.Fab")
			(hide yes)
			(effects
				(font
					(size 1 1)
					(thickness 0.15)
				)
			)
		)
		(property "Author" "Antmicro"
			(at 0 0 270)
			(unlocked yes)
			(layer "F.Fab")
			(hide yes)
			(effects
				(font
					(size 1 1)
					(thickness 0.15)
				)
			)
		)
		(property "Tolerance" "1%"
			(at 0 0 270)
			(unlocked yes)
			(layer "F.Fab")
			(hide yes)
			(effects
				(font
					(size 1 1)
					(thickness 0.15)
				)
			)
		)
		(sheetname "/CSI/")
		(sheetfile "csi.kicad_sch")
		(attr smd)
		(fp_rect
			(start -0.925 -0.47)
			(end 0.925 0.47)
			(stroke
				(width 0.05)
				(type default)
			)
			(fill no)
			(layer "F.CrtYd")
		)
		(fp_rect
			(start -0.5 -0.25)
			(end 0.5 0.25)
			(stroke
				(width 0.15)
				(type solid)
			)
			(fill no)
			(layer "F.Fab")
		)
		(fp_text user "Author: Antmicro"
			(at -0.95 4.169 90)
			(layer "F.Fab")
			(effects
				(font
					(size 0.7 0.7)
					(thickness 0.15)
				)
				(justify right top)
			)
		)
		(fp_text user "License: Apache-2.0"
			(at -0.95 5.169 90)
			(layer "F.Fab")
			(effects
				(font
					(size 0.7 0.7)
					(thickness 0.15)
				)
				(justify right top)
			)
		)
		(fp_text user "${REFERENCE}"
			(at -0.95 3.168 90)
			(layer "F.Fab")
			(effects
				(font
					(size 0.7 0.7)
					(thickness 0.15)
				)
				(justify right top)
			)
		)
		(pad "1" smd roundrect
			(at -0.48 0 270)
			(size 0.59 0.64)
			(layers "F.Cu" "F.Mask" "F.Paste")
			(roundrect_rratio 0.25)
			(net 1 "GND")
			(pintype "passive")
		)
		(pad "2" smd roundrect
			(at 0.48 0 270)
			(size 0.59 0.64)
			(layers "F.Cu" "F.Mask" "F.Paste")
			(roundrect_rratio 0.25)
			(net 996 "/CSI/CSIA_3V3_ISET")
			(pintype "passive")
		)
	)
)
